(kicad_pcb
	(version 20260206)
	(generator "pcbnew")
	(generator_version "10.0")
	(general
		(thickness 1.6)
		(legacy_teardrops no)
	)
	(paper "A4")
	(title_block
		(title "03242023_DA0F0TMBIJ0_F0T_Motherboard_J_brd_V01_OCP.brd")
		(comment 1 "Grand Teton / footprints 3665-3671 of 6105")
	)
	(layers
		(0 "F.Cu" signal "TOP")
		(4 "In1.Cu" signal "GND")
		(6 "In2.Cu" signal "IN1")
		(8 "In3.Cu" signal "GND1")
		(10 "In4.Cu" signal "IN2")
		(12 "In5.Cu" signal "GND2")
		(14 "In6.Cu" signal "IN3")
		(16 "In7.Cu" signal "GND3")
		(18 "In8.Cu" signal "VCC")
		(20 "In9.Cu" signal "VCC1")
		(22 "In10.Cu" signal "GND4")
		(24 "In11.Cu" signal "IN4")
		(26 "In12.Cu" signal "GND5")
		(28 "In13.Cu" signal "IN5")
		(30 "In14.Cu" signal "GND6")
		(32 "In15.Cu" signal "IN6")
		(34 "In16.Cu" signal "GND7")
		(2 "B.Cu" signal "BOTTOM")
		(9 "F.Adhes" user "F.Adhesive")
		(11 "B.Adhes" user "B.Adhesive")
		(13 "F.Paste" user "Package Geometry/Pastemask Top")
		(15 "B.Paste" user "Package Geometry/Pastemask Bottom")
		(5 "F.SilkS" user "Ref Des/Silkscreen Top")
		(7 "B.SilkS" user "Ref Des/Silkscreen Bottom")
		(1 "F.Mask" user "Board Geometry/Soldermask Top")
		(3 "B.Mask" user "Board Geometry/Soldermask Bottom")
		(17 "Dwgs.User" user "User.Drawings")
		(19 "Cmts.User" user "User.Comments")
		(21 "Eco1.User" user "User.Eco1")
		(23 "Eco2.User" user "User.Eco2")
		(25 "Edge.Cuts" user "Board Geometry/Outline")
		(27 "Margin" user)
		(31 "F.CrtYd" user "Package Geometry/Place Bound Top")
		(29 "B.CrtYd" user "Package Geometry/Place Bound Bottom")
		(35 "F.Fab" user "Ref Des/Assembly Top")
		(33 "B.Fab" user "Ref Des/Assembly Bottom")
	)
	(footprint ""
		(layer "F.Cu")
		(at 85.919818 -53.880258 -90)
		(property "Reference" "PC2151"
			(at 0 0 270)
			(layer "F.SilkS")
			(hide yes)
			(effects
				(font
					(size 1.27 1.27)
				)
			)
		)
		(property "Value" ""
			(at 0 0 270)
			(layer "F.Fab")
			(effects
				(font
					(size 1.27 1.27)
				)
			)
		)
		(duplicate_pad_numbers_are_jumpers no)
		(fp_line
			(start -0.7874 0.4064)
			(end -0.7874 -0.4064)
			(stroke
				(width 0.1524)
				(type default)
			)
			(layer "F.SilkS")
		)
		(fp_line
			(start 0.7874 0.4064)
			(end -0.7874 0.4064)
			(stroke
				(width 0.1524)
				(type default)
			)
			(layer "F.SilkS")
		)
		(fp_line
			(start -0.7874 -0.4064)
			(end 0.7874 -0.4064)
			(stroke
				(width 0.1524)
				(type default)
			)
			(layer "F.SilkS")
		)
		(fp_line
			(start 0.7874 -0.4064)
			(end 0.7874 0.4064)
			(stroke
				(width 0.1524)
				(type default)
			)
			(layer "F.SilkS")
		)
		(fp_line
			(start -0.67945 0.3048)
			(end -0.67945 -0.305054)
			(stroke
				(width 0.1)
				(type default)
			)
			(layer "F.Fab")
		)
		(fp_line
			(start -0.12065 0.3048)
			(end -0.67945 0.3048)
			(stroke
				(width 0.1)
				(type default)
			)
			(layer "F.Fab")
		)
		(fp_line
			(start 0.120396 0.3048)
			(end 0.120396 0.2794)
			(stroke
				(width 0.1)
				(type default)
			)
			(layer "F.Fab")
		)
		(fp_line
			(start 0.67945 0.3048)
			(end 0.120396 0.3048)
			(stroke
				(width 0.1)
				(type default)
			)
			(layer "F.Fab")
		)
		(fp_line
			(start -0.12065 0.2794)
			(end -0.12065 0.3048)
			(stroke
				(width 0.1)
				(type default)
			)
			(layer "F.Fab")
		)
		(fp_line
			(start 0.120396 0.2794)
			(end -0.12065 0.2794)
			(stroke
				(width 0.1)
				(type default)
			)
			(layer "F.Fab")
		)
		(fp_line
			(start -0.12065 -0.2794)
			(end 0.12065 -0.2794)
			(stroke
				(width 0.1)
				(type default)
			)
			(layer "F.Fab")
		)
		(fp_line
			(start 0.12065 -0.2794)
			(end 0.12065 -0.3048)
			(stroke
				(width 0.1)
				(type default)
			)
			(layer "F.Fab")
		)
		(fp_line
			(start 0.12065 -0.3048)
			(end 0.67945 -0.3048)
			(stroke
				(width 0.1)
				(type default)
			)
			(layer "F.Fab")
		)
		(fp_line
			(start 0.67945 -0.3048)
			(end 0.67945 0.3048)
			(stroke
				(width 0.1)
				(type default)
			)
			(layer "F.Fab")
		)
		(fp_line
			(start -0.67945 -0.305054)
			(end -0.12065 -0.305054)
			(stroke
				(width 0.1)
				(type default)
			)
			(layer "F.Fab")
		)
		(fp_line
			(start -0.12065 -0.305054)
			(end -0.12065 -0.2794)
			(stroke
				(width 0.1)
				(type default)
			)
			(layer "F.Fab")
		)
		(pad "1" smd circle
			(at -0.40005 0 270)
			(size 0 0)
			(layers "F.Cu" "F.Mask" "F.Paste")
			(net "P3V3_OCP_GATE_2")
		)
		(pad "2" smd circle
			(at 0.40005 0 270)
			(size 0 0)
			(layers "F.Cu" "F.Mask" "F.Paste")
			(net "GND")
		)
	)
	(footprint ""
		(layer "F.Cu")
		(at 353.246944 -241.976656 -90)
		(property "Reference" "C1015"
			(at 0 0 270)
			(layer "F.SilkS")
			(hide yes)
			(effects
				(font
					(size 1.27 1.27)
				)
			)
		)
		(property "Value" ""
			(at 0 0 270)
			(layer "F.Fab")
			(effects
				(font
					(size 1.27 1.27)
				)
			)
		)
		(duplicate_pad_numbers_are_jumpers no)
		(fp_line
			(start -0.7874 0.4064)
			(end -0.7874 -0.4064)
			(stroke
				(width 0.1524)
				(type default)
			)
			(layer "F.SilkS")
		)
		(fp_line
			(start 0.7874 0.4064)
			(end -0.7874 0.4064)
			(stroke
				(width 0.1524)
				(type default)
			)
			(layer "F.SilkS")
		)
		(fp_line
			(start -0.7874 -0.4064)
			(end 0.7874 -0.4064)
			(stroke
				(width 0.1524)
				(type default)
			)
			(layer "F.SilkS")
		)
		(fp_line
			(start 0.7874 -0.4064)
			(end 0.7874 0.4064)
			(stroke
				(width 0.1524)
				(type default)
			)
			(layer "F.SilkS")
		)
		(fp_line
			(start -0.67945 0.3048)
			(end -0.67945 -0.305054)
			(stroke
				(width 0.1)
				(type default)
			)
			(layer "F.Fab")
		)
		(fp_line
			(start -0.12065 0.3048)
			(end -0.67945 0.3048)
			(stroke
				(width 0.1)
				(type default)
			)
			(layer "F.Fab")
		)
		(fp_line
			(start 0.120396 0.3048)
			(end 0.120396 0.2794)
			(stroke
				(width 0.1)
				(type default)
			)
			(layer "F.Fab")
		)
		(fp_line
			(start 0.67945 0.3048)
			(end 0.120396 0.3048)
			(stroke
				(width 0.1)
				(type default)
			)
			(layer "F.Fab")
		)
		(fp_line
			(start -0.12065 0.2794)
			(end -0.12065 0.3048)
			(stroke
				(width 0.1)
				(type default)
			)
			(layer "F.Fab")
		)
		(fp_line
			(start 0.120396 0.2794)
			(end -0.12065 0.2794)
			(stroke
				(width 0.1)
				(type default)
			)
			(layer "F.Fab")
		)
		(fp_line
			(start -0.12065 -0.2794)
			(end 0.12065 -0.2794)
			(stroke
				(width 0.1)
				(type default)
			)
			(layer "F.Fab")
		)
		(fp_line
			(start 0.12065 -0.2794)
			(end 0.12065 -0.3048)
			(stroke
				(width 0.1)
				(type default)
			)
			(layer "F.Fab")
		)
		(fp_line
			(start 0.12065 -0.3048)
			(end 0.67945 -0.3048)
			(stroke
				(width 0.1)
				(type default)
			)
			(layer "F.Fab")
		)
		(fp_line
			(start 0.67945 -0.3048)
			(end 0.67945 0.3048)
			(stroke
				(width 0.1)
				(type default)
			)
			(layer "F.Fab")
		)
		(fp_line
			(start -0.67945 -0.305054)
			(end -0.12065 -0.305054)
			(stroke
				(width 0.1)
				(type default)
			)
			(layer "F.Fab")
		)
		(fp_line
			(start -0.12065 -0.305054)
			(end -0.12065 -0.2794)
			(stroke
				(width 0.1)
				(type default)
			)
			(layer "F.Fab")
		)
		(pad "1" smd circle
			(at -0.40005 0 270)
			(size 0 0)
			(layers "F.Cu" "F.Mask" "F.Paste")
			(net "PVCCIN_CPU0")
		)
		(pad "2" smd circle
			(at 0.40005 0 270)
			(size 0 0)
			(layers "F.Cu" "F.Mask" "F.Paste")
			(net "GND")
		)
	)
	(footprint ""
		(layer "F.Cu")
		(at 309.57774 -430.73701 -90)
		(property "Reference" "C2266"
			(at 0 0 270)
			(layer "F.SilkS")
			(hide yes)
			(effects
				(font
					(size 1.27 1.27)
				)
			)
		)
		(property "Value" ""
			(at 0 0 270)
			(layer "F.Fab")
			(effects
				(font
					(size 1.27 1.27)
				)
			)
		)
		(duplicate_pad_numbers_are_jumpers no)
		(fp_line
			(start -0.7874 0.4064)
			(end -0.7874 -0.4064)
			(stroke
				(width 0.1524)
				(type default)
			)
			(layer "F.SilkS")
		)
		(fp_line
			(start 0.7874 0.4064)
			(end -0.7874 0.4064)
			(stroke
				(width 0.1524)
				(type default)
			)
			(layer "F.SilkS")
		)
		(fp_line
			(start -0.7874 -0.4064)
			(end 0.7874 -0.4064)
			(stroke
				(width 0.1524)
				(type default)
			)
			(layer "F.SilkS")
		)
		(fp_line
			(start 0.7874 -0.4064)
			(end 0.7874 0.4064)
			(stroke
				(width 0.1524)
				(type default)
			)
			(layer "F.SilkS")
		)
		(fp_line
			(start -0.67945 0.3048)
			(end -0.67945 -0.305054)
			(stroke
				(width 0.1)
				(type default)
			)
			(layer "F.Fab")
		)
		(fp_line
			(start -0.12065 0.3048)
			(end -0.67945 0.3048)
			(stroke
				(width 0.1)
				(type default)
			)
			(layer "F.Fab")
		)
		(fp_line
			(start 0.120396 0.3048)
			(end 0.120396 0.2794)
			(stroke
				(width 0.1)
				(type default)
			)
			(layer "F.Fab")
		)
		(fp_line
			(start 0.67945 0.3048)
			(end 0.120396 0.3048)
			(stroke
				(width 0.1)
				(type default)
			)
			(layer "F.Fab")
		)
		(fp_line
			(start -0.12065 0.2794)
			(end -0.12065 0.3048)
			(stroke
				(width 0.1)
				(type default)
			)
			(layer "F.Fab")
		)
		(fp_line
			(start 0.120396 0.2794)
			(end -0.12065 0.2794)
			(stroke
				(width 0.1)
				(type default)
			)
			(layer "F.Fab")
		)
		(fp_line
			(start -0.12065 -0.2794)
			(end 0.12065 -0.2794)
			(stroke
				(width 0.1)
				(type default)
			)
			(layer "F.Fab")
		)
		(fp_line
			(start 0.12065 -0.2794)
			(end 0.12065 -0.3048)
			(stroke
				(width 0.1)
				(type default)
			)
			(layer "F.Fab")
		)
		(fp_line
			(start 0.12065 -0.3048)
			(end 0.67945 -0.3048)
			(stroke
				(width 0.1)
				(type default)
			)
			(layer "F.Fab")
		)
		(fp_line
			(start 0.67945 -0.3048)
			(end 0.67945 0.3048)
			(stroke
				(width 0.1)
				(type default)
			)
			(layer "F.Fab")
		)
		(fp_line
			(start -0.67945 -0.305054)
			(end -0.12065 -0.305054)
			(stroke
				(width 0.1)
				(type default)
			)
			(layer "F.Fab")
		)
		(fp_line
			(start -0.12065 -0.305054)
			(end -0.12065 -0.2794)
			(stroke
				(width 0.1)
				(type default)
			)
			(layer "F.Fab")
		)
		(pad "1" smd circle
			(at -0.40005 0 270)
			(size 0 0)
			(layers "F.Cu" "F.Mask" "F.Paste")
			(net "GPU_3V3IO_RSVD1_FFU_ISO")
		)
		(pad "2" smd circle
			(at 0.40005 0 270)
			(size 0 0)
			(layers "F.Cu" "F.Mask" "F.Paste")
			(net "GND")
		)
	)
	(footprint ""
		(layer "F.Cu")
		(at 152.96388 -130.774948)
		(property "Reference" "R3207"
			(at 0 0 0)
			(layer "F.SilkS")
			(hide yes)
			(effects
				(font
					(size 1.27 1.27)
				)
			)
		)
		(property "Value" ""
			(at 0 0 0)
			(layer "F.Fab")
			(effects
				(font
					(size 1.27 1.27)
				)
			)
		)
		(duplicate_pad_numbers_are_jumpers no)
		(fp_line
			(start -0.7874 -0.4064)
			(end 0.7874 -0.4064)
			(stroke
				(width 0.1524)
				(type default)
			)
			(layer "F.SilkS")
		)
		(fp_line
			(start -0.7874 0.4064)
			(end -0.7874 -0.4064)
			(stroke
				(width 0.1524)
				(type default)
			)
			(layer "F.SilkS")
		)
		(fp_line
			(start 0.7874 -0.4064)
			(end 0.7874 0.4064)
			(stroke
				(width 0.1524)
				(type default)
			)
			(layer "F.SilkS")
		)
		(fp_line
			(start 0.7874 0.4064)
			(end -0.7874 0.4064)
			(stroke
				(width 0.1524)
				(type default)
			)
			(layer "F.SilkS")
		)
		(fp_line
			(start -0.67945 -0.305054)
			(end -0.12065 -0.305054)
			(stroke
				(width 0.1)
				(type default)
			)
			(layer "F.Fab")
		)
		(fp_line
			(start -0.67945 0.3048)
			(end -0.67945 -0.305054)
			(stroke
				(width 0.1)
				(type default)
			)
			(layer "F.Fab")
		)
		(fp_line
			(start -0.12065 -0.305054)
			(end -0.12065 -0.2794)
			(stroke
				(width 0.1)
				(type default)
			)
			(layer "F.Fab")
		)
		(fp_line
			(start -0.12065 -0.2794)
			(end 0.12065 -0.2794)
			(stroke
				(width 0.1)
				(type default)
			)
			(layer "F.Fab")
		)
		(fp_line
			(start -0.12065 0.2794)
			(end -0.12065 0.3048)
			(stroke
				(width 0.1)
				(type default)
			)
			(layer "F.Fab")
		)
		(fp_line
			(start -0.12065 0.3048)
			(end -0.67945 0.3048)
			(stroke
				(width 0.1)
				(type default)
			)
			(layer "F.Fab")
		)
		(fp_line
			(start 0.120396 0.2794)
			(end -0.12065 0.2794)
			(stroke
				(width 0.1)
				(type default)
			)
			(layer "F.Fab")
		)
		(fp_line
			(start 0.120396 0.3048)
			(end 0.120396 0.2794)
			(stroke
				(width 0.1)
				(type default)
			)
			(layer "F.Fab")
		)
		(fp_line
			(start 0.12065 -0.3048)
			(end 0.67945 -0.3048)
			(stroke
				(width 0.1)
				(type default)
			)
			(layer "F.Fab")
		)
		(fp_line
			(start 0.12065 -0.2794)
			(end 0.12065 -0.3048)
			(stroke
				(width 0.1)
				(type default)
			)
			(layer "F.Fab")
		)
		(fp_line
			(start 0.67945 -0.3048)
			(end 0.67945 0.3048)
			(stroke
				(width 0.1)
				(type default)
			)
			(layer "F.Fab")
		)
		(fp_line
			(start 0.67945 0.3048)
			(end 0.120396 0.3048)
			(stroke
				(width 0.1)
				(type default)
			)
			(layer "F.Fab")
		)
		(pad "1" smd circle
			(at -0.40005 0)
			(size 0 0)
			(layers "F.Cu" "F.Mask" "F.Paste")
			(net "FB_BMC_ISOLATE1")
		)
		(pad "2" smd circle
			(at 0.40005 0)
			(size 0 0)
			(layers "F.Cu" "F.Mask" "F.Paste")
			(net "GND")
		)
	)
	(footprint ""
		(layer "F.Cu")
		(at 120.36044 -425.059348)
		(property "Reference" "R2937"
			(at 0 0 0)
			(layer "F.SilkS")
			(hide yes)
			(effects
				(font
					(size 1.27 1.27)
				)
			)
		)
		(property "Value" ""
			(at 0 0 0)
			(layer "F.Fab")
			(effects
				(font
					(size 1.27 1.27)
				)
			)
		)
		(duplicate_pad_numbers_are_jumpers no)
		(fp_line
			(start -0.7874 -0.4064)
			(end 0.7874 -0.4064)
			(stroke
				(width 0.1524)
				(type default)
			)
			(layer "F.SilkS")
		)
		(fp_line
			(start -0.7874 0.4064)
			(end -0.7874 -0.4064)
			(stroke
				(width 0.1524)
				(type default)
			)
			(layer "F.SilkS")
		)
		(fp_line
			(start 0.7874 -0.4064)
			(end 0.7874 0.4064)
			(stroke
				(width 0.1524)
				(type default)
			)
			(layer "F.SilkS")
		)
		(fp_line
			(start 0.7874 0.4064)
			(end -0.7874 0.4064)
			(stroke
				(width 0.1524)
				(type default)
			)
			(layer "F.SilkS")
		)
		(fp_line
			(start -0.67945 -0.305054)
			(end -0.12065 -0.305054)
			(stroke
				(width 0.1)
				(type default)
			)
			(layer "F.Fab")
		)
		(fp_line
			(start -0.67945 0.3048)
			(end -0.67945 -0.305054)
			(stroke
				(width 0.1)
				(type default)
			)
			(layer "F.Fab")
		)
		(fp_line
			(start -0.12065 -0.305054)
			(end -0.12065 -0.2794)
			(stroke
				(width 0.1)
				(type default)
			)
			(layer "F.Fab")
		)
		(fp_line
			(start -0.12065 -0.2794)
			(end 0.12065 -0.2794)
			(stroke
				(width 0.1)
				(type default)
			)
			(layer "F.Fab")
		)
		(fp_line
			(start -0.12065 0.2794)
			(end -0.12065 0.3048)
			(stroke
				(width 0.1)
				(type default)
			)
			(layer "F.Fab")
		)
		(fp_line
			(start -0.12065 0.3048)
			(end -0.67945 0.3048)
			(stroke
				(width 0.1)
				(type default)
			)
			(layer "F.Fab")
		)
		(fp_line
			(start 0.120396 0.2794)
			(end -0.12065 0.2794)
			(stroke
				(width 0.1)
				(type default)
			)
			(layer "F.Fab")
		)
		(fp_line
			(start 0.120396 0.3048)
			(end 0.120396 0.2794)
			(stroke
				(width 0.1)
				(type default)
			)
			(layer "F.Fab")
		)
		(fp_line
			(start 0.12065 -0.3048)
			(end 0.67945 -0.3048)
			(stroke
				(width 0.1)
				(type default)
			)
			(layer "F.Fab")
		)
		(fp_line
			(start 0.12065 -0.2794)
			(end 0.12065 -0.3048)
			(stroke
				(width 0.1)
				(type default)
			)
			(layer "F.Fab")
		)
		(fp_line
			(start 0.67945 -0.3048)
			(end 0.67945 0.3048)
			(stroke
				(width 0.1)
				(type default)
			)
			(layer "F.Fab")
		)
		(fp_line
			(start 0.67945 0.3048)
			(end 0.120396 0.3048)
			(stroke
				(width 0.1)
				(type default)
			)
			(layer "F.Fab")
		)
		(pad "1" smd circle
			(at -0.40005 0)
			(size 0 0)
			(layers "F.Cu" "F.Mask" "F.Paste")
			(net "FM_GPU_PWR_EN_R")
		)
		(pad "2" smd circle
			(at 0.40005 0)
			(size 0 0)
			(layers "F.Cu" "F.Mask" "F.Paste")
			(net "GND")
		)
	)
	(footprint ""
		(layer "F.Cu")
		(at 134.93496 -206.024734)
		(property "Reference" "H18"
			(at -1.17602 3.913632 0)
			(unlocked yes)
			(layer "F.SilkS")
			(effects
				(font
					(size 0.7874 0.5842)
					(thickness 0.1524)
				)
				(justify left)
			)
		)
		(property "Value" ""
			(at 0 0 0)
			(layer "F.Fab")
			(effects
				(font
					(size 1.27 1.27)
				)
			)
		)
		(duplicate_pad_numbers_are_jumpers no)
		(fp_circle
			(center 0 0)
			(end 2.5273 0)
			(stroke
				(width 0.1524)
				(type default)
			)
			(fill no)
			(layer "F.SilkS")
		)
		(fp_circle
			(center 0 0)
			(end 2.5273 0)
			(stroke
				(width 0.1524)
				(type default)
			)
			(fill no)
			(layer "B.SilkS")
		)
		(fp_circle
			(center 0 0)
			(end 2.5273 0)
			(stroke
				(width 0.1)
				(type default)
			)
			(fill no)
			(layer "B.Fab")
		)
		(fp_circle
			(center 0 0)
			(end 2.5273 0)
			(stroke
				(width 0.1)
				(type default)
			)
			(fill no)
			(layer "F.Fab")
		)
		(pad "" np_thru_hole circle
			(at 0 0)
			(size 3.429 3.429)
			(drill 3.429)
			(layers "*.Cu" "*.Mask")
			(clearance 0.381)
			(thermal_gap 0.381)
		)
	)
	(footprint ""
		(layer "F.Cu")
		(at 164.52088 -41.112948)
		(property "Reference" "R3301"
			(at 0 0 0)
			(layer "F.SilkS")
			(hide yes)
			(effects
				(font
					(size 1.27 1.27)
				)
			)
		)
		(property "Value" ""
			(at 0 0 0)
			(layer "F.Fab")
			(effects
				(font
					(size 1.27 1.27)
				)
			)
		)
		(duplicate_pad_numbers_are_jumpers no)
		(fp_line
			(start -0.7874 -0.4064)
			(end 0.7874 -0.4064)
			(stroke
				(width 0.1524)
				(type default)
			)
			(layer "F.SilkS")
		)
		(fp_line
			(start -0.7874 0.4064)
			(end -0.7874 -0.4064)
			(stroke
				(width 0.1524)
				(type default)
			)
			(layer "F.SilkS")
		)
		(fp_line
			(start 0.7874 -0.4064)
			(end 0.7874 0.4064)
			(stroke
				(width 0.1524)
				(type default)
			)
			(layer "F.SilkS")
		)
		(fp_line
			(start 0.7874 0.4064)
			(end -0.7874 0.4064)
			(stroke
				(width 0.1524)
				(type default)
			)
			(layer "F.SilkS")
		)
		(fp_line
			(start -0.67945 -0.305054)
			(end -0.12065 -0.305054)
			(stroke
				(width 0.1)
				(type default)
			)
			(layer "F.Fab")
		)
		(fp_line
			(start -0.67945 0.3048)
			(end -0.67945 -0.305054)
			(stroke
				(width 0.1)
				(type default)
			)
			(layer "F.Fab")
		)
		(fp_line
			(start -0.12065 -0.305054)
			(end -0.12065 -0.2794)
			(stroke
				(width 0.1)
				(type default)
			)
			(layer "F.Fab")
		)
		(fp_line
			(start -0.12065 -0.2794)
			(end 0.12065 -0.2794)
			(stroke
				(width 0.1)
				(type default)
			)
			(layer "F.Fab")
		)
		(fp_line
			(start -0.12065 0.2794)
			(end -0.12065 0.3048)
			(stroke
				(width 0.1)
				(type default)
			)
			(layer "F.Fab")
		)
		(fp_line
			(start -0.12065 0.3048)
			(end -0.67945 0.3048)
			(stroke
				(width 0.1)
				(type default)
			)
			(layer "F.Fab")
		)
		(fp_line
			(start 0.120396 0.2794)
			(end -0.12065 0.2794)
			(stroke
				(width 0.1)
				(type default)
			)
			(layer "F.Fab")
		)
		(fp_line
			(start 0.120396 0.3048)
			(end 0.120396 0.2794)
			(stroke
				(width 0.1)
				(type default)
			)
			(layer "F.Fab")
		)
		(fp_line
			(start 0.12065 -0.3048)
			(end 0.67945 -0.3048)
			(stroke
				(width 0.1)
				(type default)
			)
			(layer "F.Fab")
		)
		(fp_line
			(start 0.12065 -0.2794)
			(end 0.12065 -0.3048)
			(stroke
				(width 0.1)
				(type default)
			)
			(layer "F.Fab")
		)
		(fp_line
			(start 0.67945 -0.3048)
			(end 0.67945 0.3048)
			(stroke
				(width 0.1)
				(type default)
			)
			(layer "F.Fab")
		)
		(fp_line
			(start 0.67945 0.3048)
			(end 0.120396 0.3048)
			(stroke
				(width 0.1)
				(type default)
			)
			(layer "F.Fab")
		)
		(pad "1" smd circle
			(at -0.40005 0)
			(size 0 0)
			(layers "F.Cu" "F.Mask" "F.Paste")
			(net "IRQ_LVC3_WAKE_N")
		)
		(pad "2" smd circle
			(at 0.40005 0)
			(size 0 0)
			(layers "F.Cu" "F.Mask" "F.Paste")
			(net "M2_0_PEWAKE_N")
		)
	)
)
